# BASEBOARD_FAB2 (Tioga Pass) — schematic netlist excerpt (pin names and nets, part order shuffled) for the footprints in the layout excerpt that follows; sources: Cadence DE-HDL packaged netlist, KiCad conversion of Wiwynn_Tioga_Pass_MB.brd

C3T9  CAP  47UF 4V 20% X6S  pkg 0805  page 231 : A = PVPP_ABC ; B = GND
C3P36  CAP  0.22UF 16V 10% X7R  pkg 0402  page 107 : A = P3E_CPU0_PE1_SS_TXN<6> ; B = P3E_CPU0_PE1_SS_C_TXN<6>
R1M10  RES  0.0 5% CHIP  pkg 0402  page 177 : A = LED_PCH_SATA_HDD_N ; B = LED_SATA_ACT_R_N

(kicad_pcb
	(version 20260206)
	(generator "pcbnew")
	(generator_version "10.0")
	(general
		(thickness 1.6)
		(legacy_teardrops no)
	)
	(paper "A4")
	(title_block
		(title "Wiwynn_Tioga_Pass_MB.brd")
		(comment 1 "Tioga Pass / footprints 3762-3764 of 4770")
	)
	(layers
		(0 "F.Cu" signal "TOP")
		(4 "In1.Cu" signal "L2GND")
		(6 "In2.Cu" signal "L3")
		(8 "In3.Cu" signal "L4GND")
		(10 "In4.Cu" signal "L5")
		(12 "In5.Cu" signal "L6GND")
		(14 "In6.Cu" signal "L7VCC")
		(16 "In7.Cu" signal "L8VCC")
		(18 "In8.Cu" signal "L9GND")
		(20 "In9.Cu" signal "L10")
		(22 "In10.Cu" signal "L11GND")
		(24 "In11.Cu" signal "L12")
		(26 "In12.Cu" signal "L13GND")
		(2 "B.Cu" signal "BOTTOM")
		(9 "F.Adhes" user "F.Adhesive")
		(11 "B.Adhes" user "B.Adhesive")
		(13 "F.Paste" user "Package Geometry/Pastemask Top")
		(15 "B.Paste" user "Package Geometry/Pastemask Bottom")
		(5 "F.SilkS" user "Ref Des/Silkscreen Top")
		(7 "B.SilkS" user "Ref Des/Silkscreen Bottom")
		(1 "F.Mask" user "Board Geometry/Soldermask Top")
		(3 "B.Mask" user "Board Geometry/Soldermask Bottom")
		(17 "Dwgs.User" user "User.Drawings")
		(19 "Cmts.User" user "User.Comments")
		(21 "Eco1.User" user "User.Eco1")
		(23 "Eco2.User" user "User.Eco2")
		(25 "Edge.Cuts" user "Board Geometry/Outline")
		(27 "Margin" user)
		(31 "F.CrtYd" user "Package Geometry/Place Bound Top")
		(29 "B.CrtYd" user "Package Geometry/Place Bound Bottom")
		(35 "F.Fab" user "Ref Des/Assembly Top")
		(33 "B.Fab" user "Ref Des/Assembly Bottom")
	)
	(footprint ""
		(layer "B.Cu")
		(at 357.133398 -77.915516)
		(property "Reference" "C3P36"
			(at 0 0 0)
			(layer "B.SilkS")
			(hide yes)
			(effects
				(font
					(size 1.27 1.27)
				)
				(justify mirror)
			)
		)
		(property "Value" ""
			(at 0 0 0)
			(layer "B.Fab")
			(effects
				(font
					(size 1.27 1.27)
				)
				(justify mirror)
			)
		)
		(duplicate_pad_numbers_are_jumpers no)
		(fp_poly
			(pts
				(xy -0.3048 -0.1016) (xy -0.3048 0.9906) (xy 0.3048 0.9906) (xy 0.3048 -0.1016)
			)
			(stroke
				(width 0)
				(type default)
			)
			(fill no)
			(layer "B.CrtYd")
		)
		(fp_line
			(start -0.3048 -0.1016)
			(end 0.3048 -0.1016)
			(stroke
				(width 0.1)
				(type default)
			)
			(layer "B.Fab")
		)
		(fp_line
			(start -0.3048 0.9906)
			(end -0.3048 -0.1016)
			(stroke
				(width 0.1)
				(type default)
			)
			(layer "B.Fab")
		)
		(fp_line
			(start 0.3048 -0.1016)
			(end 0.3048 0.9906)
			(stroke
				(width 0.1)
				(type default)
			)
			(layer "B.Fab")
		)
		(fp_line
			(start 0.3048 0.9906)
			(end -0.3048 0.9906)
			(stroke
				(width 0.1)
				(type default)
			)
			(layer "B.Fab")
		)
		(pad "1" smd rect
			(at 0 0 180)
			(size 0.508 0.508)
			(layers "B.Cu" "B.Mask" "B.Paste")
			(net "P3E_CPU0_PE1_SS_TXN<6>")
		)
		(pad "2" smd rect
			(at 0 0.889 180)
			(size 0.508 0.508)
			(layers "B.Cu" "B.Mask" "B.Paste")
			(net "P3E_CPU0_PE1_SS_C_TXN<6>")
		)
		(zone
			(layer "B.Cu")
			(hatch none 0.5)
			(connect_pads
				(clearance 0)
			)
			(min_thickness 0.25)
			(keepout
				(tracks allowed)
				(vias not_allowed)
				(pads allowed)
				(copperpour not_allowed)
				(footprints allowed)
			)
			(placement
				(enabled no)
				(sheetname "")
			)
			(fill
				(thermal_gap 0.5)
				(thermal_bridge_width 0.5)
				(island_removal_mode 0)
			)
			(polygon
				(pts
					(xy 357.387398 -77.661516) (xy 356.879398 -77.661516) (xy 356.879398 -77.280516) (xy 357.387398 -77.280516)
				)
			)
		)
		(zone
			(layer "B.Cu")
			(hatch none 0.5)
			(connect_pads
				(clearance 0)
			)
			(min_thickness 0.25)
			(keepout
				(tracks not_allowed)
				(vias allowed)
				(pads allowed)
				(copperpour not_allowed)
				(footprints allowed)
			)
			(placement
				(enabled no)
				(sheetname "")
			)
			(fill
				(thermal_gap 0.5)
				(thermal_bridge_width 0.5)
				(island_removal_mode 0)
			)
			(polygon
				(pts
					(xy 357.387398 -77.280516) (xy 356.879398 -77.280516) (xy 356.879398 -77.661516) (xy 357.387398 -77.661516)
				)
			)
		)
	)
	(footprint ""
		(layer "B.Cu")
		(at 333.6798 -28.3083 90)
		(property "Reference" "C3T9"
			(at 0 0 90)
			(layer "B.SilkS")
			(hide yes)
			(effects
				(font
					(size 1.27 1.27)
				)
				(justify mirror)
			)
		)
		(property "Value" ""
			(at 0 0 90)
			(layer "B.Fab")
			(effects
				(font
					(size 1.27 1.27)
				)
				(justify mirror)
			)
		)
		(duplicate_pad_numbers_are_jumpers no)
		(fp_rect
			(start -0.7239 -0.2159)
			(end 0.7239 1.9939)
			(stroke
				(width 0)
				(type default)
			)
			(fill no)
			(layer "B.CrtYd")
		)
		(fp_line
			(start 0.7239 -0.2159)
			(end 0.7239 1.9939)
			(stroke
				(width 0.1)
				(type default)
			)
			(layer "B.Fab")
		)
		(fp_line
			(start -0.7239 -0.2159)
			(end 0.7239 -0.2159)
			(stroke
				(width 0.1)
				(type default)
			)
			(layer "B.Fab")
		)
		(fp_line
			(start 0.7239 1.9939)
			(end -0.7239 1.9939)
			(stroke
				(width 0.1)
				(type default)
			)
			(layer "B.Fab")
		)
		(fp_line
			(start -0.7239 1.9939)
			(end -0.7239 -0.2159)
			(stroke
				(width 0.1)
				(type default)
			)
			(layer "B.Fab")
		)
		(pad "1" smd rect
			(at 0 0 270)
			(size 1.27 1.016)
			(layers "B.Cu" "B.Mask" "B.Paste")
			(net "PVPP_ABC")
		)
		(pad "2" smd rect
			(at 0 1.778 270)
			(size 1.27 1.016)
			(layers "B.Cu" "B.Mask" "B.Paste")
			(net "GND")
		)
		(zone
			(layer "B.Cu")
			(hatch none 0.5)
			(connect_pads
				(clearance 0)
			)
			(min_thickness 0.25)
			(keepout
				(tracks not_allowed)
				(vias allowed)
				(pads allowed)
				(copperpour not_allowed)
				(footprints allowed)
			)
			(placement
				(enabled no)
				(sheetname "")
			)
			(fill
				(thermal_gap 0.5)
				(thermal_bridge_width 0.5)
				(island_removal_mode 0)
			)
			(polygon
				(pts
					(xy 334.1878 -27.6733) (xy 334.9498 -27.6733) (xy 334.9498 -28.9433) (xy 334.1878 -28.9433)
				)
			)
		)
	)
	(footprint ""
		(layer "B.Cu")
		(at 496.17376 -124.0663 180)
		(property "Reference" "R1M10"
			(at 0 0 0)
			(layer "B.SilkS")
			(hide yes)
			(effects
				(font
					(size 1.27 1.27)
				)
				(justify mirror)
			)
		)
		(property "Value" ""
			(at 0 0 0)
			(layer "B.Fab")
			(effects
				(font
					(size 1.27 1.27)
				)
				(justify mirror)
			)
		)
		(duplicate_pad_numbers_are_jumpers no)
		(fp_poly
			(pts
				(xy 0.2794 -0.1016) (xy -0.2794 -0.1016) (xy -0.2794 0.9906) (xy 0.2794 0.9906)
			)
			(stroke
				(width 0)
				(type default)
			)
			(fill no)
			(layer "B.CrtYd")
		)
		(fp_line
			(start 0.2794 0.9906)
			(end -0.2794 0.9906)
			(stroke
				(width 0.1)
				(type default)
			)
			(layer "B.Fab")
		)
		(fp_line
			(start 0.2794 -0.1016)
			(end 0.2794 0.9906)
			(stroke
				(width 0.1)
				(type default)
			)
			(layer "B.Fab")
		)
		(fp_line
			(start -0.2794 0.9906)
			(end -0.2794 -0.1016)
			(stroke
				(width 0.1)
				(type default)
			)
			(layer "B.Fab")
		)
		(fp_line
			(start -0.2794 -0.1016)
			(end 0.2794 -0.1016)
			(stroke
				(width 0.1)
				(type default)
			)
			(layer "B.Fab")
		)
		(pad "1" smd rect
			(at 0 0)
			(size 0.508 0.508)
			(layers "B.Cu" "B.Mask" "B.Paste")
			(net "LED_PCH_SATA_HDD_N")
		)
		(pad "2" smd rect
			(at 0 0.889)
			(size 0.508 0.508)
			(layers "B.Cu" "B.Mask" "B.Paste")
			(net "LED_SATA_ACT_R_N")
		)
		(zone
			(layer "B.Cu")
			(hatch none 0.5)
			(connect_pads
				(clearance 0)
			)
			(min_thickness 0.25)
			(keepout
				(tracks not_allowed)
				(vias allowed)
				(pads allowed)
				(copperpour not_allowed)
				(footprints allowed)
			)
			(placement
				(enabled no)
				(sheetname "")
			)
			(fill
				(thermal_gap 0.5)
				(thermal_bridge_width 0.5)
				(island_removal_mode 0)
			)
			(polygon
				(pts
					(xy 495.91976 -124.7013) (xy 496.42776 -124.7013) (xy 496.42776 -124.3203) (xy 495.91976 -124.3203)
				)
			)
		)
		(zone
			(layer "B.Cu")
			(hatch none 0.5)
			(connect_pads
				(clearance 0)
			)
			(min_thickness 0.25)
			(keepout
				(tracks allowed)
				(vias not_allowed)
				(pads allowed)
				(copperpour not_allowed)
				(footprints allowed)
			)
			(placement
				(enabled no)
				(sheetname "")
			)
			(fill
				(thermal_gap 0.5)
				(thermal_bridge_width 0.5)
				(island_removal_mode 0)
			)
			(polygon
				(pts
					(xy 495.91976 -124.3203) (xy 496.42776 -124.3203) (xy 496.42776 -124.7013) (xy 495.91976 -124.7013)
				)
			)
		)
	)
)
